#ISCELL
  mstr_misc dns *
  *
#ISCELL
  pure_quanta quanta_title_block_c *
  *
#ISCELL
  standard offpage *
  page217_i1
#ISCELL
  standard offpage *
  page217_i10
#ISCELL
  standard offpage *
  page217_i11
#ISCELL
  logical_power universal_gnd *
  page217_i12
#CELL
  pure_quanta q_res *
  page217_i13
#ISCELL
  standard offpage *
  page217_i14
#ISCELL
  standard offpage *
  page217_i15
#CELL
  pure_quanta q_res *
  page217_i16
#CELL
  pure_quanta q_res *
  page217_i17
#CELL
  pure_quanta q_res *
  page217_i18
#CELL
  pure_quanta qs3vh257qg8 *
  page217_i19
#ISCELL
  standard offpage *
  page217_i2
#CELL
  pure_quanta q_res *
  page217_i20
#ISCELL
  logical_power universal_gnd *
  page217_i21
#ISCELL
  logical_power universal_gnd *
  page217_i22
#ISCELL
  logical_power universal_power *
  page217_i23
#CELL
  pure_quanta q_cap *
  page217_i24
#CELL
  pure_quanta q_res *
  page217_i25
#CELL
  pure_quanta q_res *
  page217_i26
#ISCELL
  standard offpage *
  page217_i27
#ISCELL
  standard offpage *
  page217_i28
#CELL
  pure_quanta q_res *
  page217_i29
#CELL
  pure_quanta q_res *
  page217_i30
#ISCELL
  logical_power universal_power *
  page217_i31
#CELL
  pure_quanta q_res *
  page217_i32
#CELL
  pure_quanta q_res *
  page217_i33
#CELL
  pure_quanta q_res *
  page217_i34
#CELL
  pure_quanta q_res *
  page217_i35
#ISCELL
  standard offpage *
  page217_i36
#CELL
  pure_quanta q_res *
  page217_i37
#CELL
  pure_quanta q_res *
  page217_i38
#CELL
  pure_quanta q_res *
  page217_i39
#ISCELL
  standard offpage *
  page217_i4
#CELL
  pure_quanta q_res *
  page217_i40
#ISCELL
  logical_power universal_gnd *
  page217_i41
#CELL
  pure_quanta q_res *
  page217_i42
#CELL
  pure_quanta q_res *
  page217_i43
#ISCELL
  logical_power universal_power *
  page217_i44
#ISCELL
  standard offpage *
  page217_i45
#ISCELL
  standard offpage *
  page217_i46
#ISCELL
  standard offpage *
  page217_i47
#ISCELL
  standard offpage *
  page217_i48
#ISCELL
  standard offpage *
  page217_i49
#ISCELL
  standard offpage *
  page217_i5
#ISCELL
  standard offpage *
  page217_i50
#ISCELL
  standard offpage *
  page217_i51
#ISCELL
  standard offpage *
  page217_i52
#CELL
  pure_quanta q_res *
  page217_i53
#ISCELL
  standard offpage *
  page217_i6
#ISCELL
  standard offpage *
  page217_i7
#ISCELL
  standard offpage *
  page217_i8
#ISCELL
  standard offpage *
  page217_i9
